#ISCELL
  mstr_symbols intel_corp_bpage *
  *
#CELL
  mstr_discrete cap *
  page150_i1
#CELL
  w_hdl scd1u16v2kx-3gp *
  page150_i10
#ISCELL
  mstr_symbols gnd *
  page150_i11
#CELL
  mstr_discrete cap *
  page150_i12
#CELL
  mstr_discrete cap *
  page150_i13
#CELL
  mstr_discrete cap *
  page150_i14
#ISCELL
  w_power w_vcc_circle *
  page150_i15
#ISCELL
  mstr_symbols gnd *
  page150_i16
#CELL
  w_hdl sc4d7u10v3kx-gp *
  page150_i17
#CELL
  w_hdl scd1u16v2kx-3gp *
  page150_i18
#CELL
  mstr_discrete cap *
  page150_i19
#CELL
  w_hdl sc4d7u10v3kx-gp *
  page150_i2
#ISCELL
  w_power w_vcc_circle *
  page150_i20
#CELL
  w_hdl sc4d7u10v3kx-gp *
  page150_i21
#ISCELL
  mstr_symbols gnd *
  page150_i22
#ISCELL
  mstr_symbols gnd *
  page150_i23
#CELL
  w_hdl scd1u16v2kx-3gp *
  page150_i24
#CELL
  mstr_discrete cap *
  page150_i25
#CELL
  w_hdl hcb1608kf-800t30-gp *
  page150_i26
#ISCELL
  w_power w_vcc_circle *
  page150_i27
#CELL
  w_hdl sc4d7u10v3kx-gp *
  page150_i28
#ISCELL
  mstr_symbols gnd *
  page150_i29
#ISCELL
  w_power w_vcc_circle *
  page150_i3
#CELL
  w_hdl scd1u16v2kx-3gp *
  page150_i30
#CELL
  mstr_discrete cap *
  page150_i31
#CELL
  w_hdl hcb1608kf-800t30-gp *
  page150_i32
#CELL
  mstr_discrete cap *
  page150_i33
#ISCELL
  w_power w_vcc_circle *
  page150_i34
#CELL
  mstr_discrete cap *
  page150_i35
#CELL
  w_hdl scd1u16v2kx-3gp *
  page150_i36
#ISCELL
  mstr_symbols p3v3_stby *
  page150_i37
#CELL
  mstr_discrete cap *
  page150_i38
#CELL
  w_hdl hcb1608kf-800t30-gp *
  page150_i39
#CELL
  mstr_discrete cap *
  page150_i4
#ISCELL
  mstr_symbols p3v3_stby *
  page150_i40
#ISCELL
  mstr_symbols p3v3_stby *
  page150_i41
#ISCELL
  w_power w_vcc_circle *
  page150_i42
#CELL
  w_hdl sc4d7u10v3kx-gp *
  page150_i43
#ISCELL
  mstr_symbols gnd *
  page150_i44
#CELL
  mstr_discrete cap *
  page150_i45
#CELL
  mstr_discrete cap *
  page150_i46
#ISCELL
  mstr_symbols p3v3_stby *
  page150_i47
#CELL
  mstr_discrete cap *
  page150_i48
#ISCELL
  w_power w_vcc_circle *
  page150_i49
#ISCELL
  mstr_symbols gnd *
  page150_i5
#CELL
  w_hdl sc4d7u10v3kx-gp *
  page150_i50
#CELL
  mstr_discrete cap *
  page150_i51
#ISCELL
  mstr_symbols gnd *
  page150_i52
#CELL
  w_hdl scd1u16v2kx-3gp *
  page150_i53
#CELL
  w_hdl sc4d7u10v3kx-gp *
  page150_i54
#CELL
  mstr_discrete cap *
  page150_i55
#ISCELL
  mstr_symbols gnd *
  page150_i56
#CELL
  w_hdl 0r3j-0-u-gp *
  page150_i57
#ISCELL
  w_power w_vcc_circle *
  page150_i58
#CELL
  mstr_discrete cap *
  page150_i59
#CELL
  w_hdl sc4d7u10v3kx-gp *
  page150_i6
#ISCELL
  mstr_symbols gnd *
  page150_i60
#CELL
  w_hdl scd1u16v2kx-3gp *
  page150_i61
#CELL
  mstr_discrete cap *
  page150_i62
#CELL
  mstr_discrete cap *
  page150_i63
#ISCELL
  w_power w_vcc_circle *
  page150_i64
#CELL
  w_hdl sc4d7u10v3kx-gp *
  page150_i65
#ISCELL
  mstr_symbols gnd *
  page150_i66
#CELL
  w_hdl scd1u16v2kx-3gp *
  page150_i67
#ISCELL
  mstr_symbols p3v3_stby *
  page150_i68
#CELL
  w_hdl sc4d7u10v3kx-gp *
  page150_i69
#CELL
  w_hdl 0r3j-0-u-gp *
  page150_i7
#ISCELL
  mstr_symbols gnd *
  page150_i70
#CELL
  mstr_discrete cap *
  page150_i71
#CELL
  mstr_discrete cap *
  page150_i72
#CELL
  mstr_discrete cap *
  page150_i73
#ISCELL
  w_power w_vcc_circle *
  page150_i74
#CELL
  mstr_discrete cap *
  page150_i75
#CELL
  w_hdl hcb1608kf-800t30-gp *
  page150_i76
#ISCELL
  mstr_symbols p3v3_stby *
  page150_i77
#CELL
  mstr_discrete cap *
  page150_i78
#CELL
  w_hdl scd1u16v2kx-3gp *
  page150_i79
#ISCELL
  mstr_symbols p3v3_stby *
  page150_i8
#CELL
  mstr_discrete cap *
  page150_i80
#CELL
  mstr_discrete cap *
  page150_i81
#CELL
  mstr_discrete cap *
  page150_i82
#ISCELL
  mstr_symbols p3v3_stby *
  page150_i83
#CELL
  w_hdl hcb1608kf-800t30-gp *
  page150_i84
#CELL
  w_hdl scd1u16v2kx-3gp *
  page150_i85
#CELL
  mstr_discrete cap *
  page150_i86
#CELL
  mstr_discrete cap *
  page150_i87
#ISCELL
  mstr_symbols p3v3_stby *
  page150_i88
#CELL
  w_hdl hcb1608kf-800t30-gp *
  page150_i89
#ISCELL
  w_power w_vcc_circle *
  page150_i9
